# S9S_MB_2U (Grand Teton) — schematic netlist excerpt (pin names and nets, part order shuffled) for the footprints in the layout excerpt that follows; sources: Cadence DE-HDL packaged netlist, KiCad conversion of 03242023_DA0F0TMBIJ0_F0T_Motherboard_J_brd_V01_OCP.brd

D92  Q_LED  IC  pkg SMLF  page 252 : A = LED_PWRGD_P1V05_PCH_AUX ; C = LED_PWRGD_P1V05_PCH_AUX_D

PR2534  Q_SP_RES4P  0.0003 1% EMPTY  pkg R2725_4P  page 304
  \1a\  = P12V_PSU
  \1b\  = P12V_HSC_SENSE2_R4_P
  \2a\  = P12V_MAIN_R
  \2b\  = P12V_HSC_SENSE2_R4_N

R3594  Q_RES  33.2 1% CHIP  pkg 0402LF  page 232 : A = SMB_INA230_3V3AUX_SCL ; B = SMB_INA230_4_3V3AUX_SCL_R

(kicad_pcb
	(version 20260206)
	(generator "pcbnew")
	(generator_version "10.0")
	(general
		(thickness 1.6)
		(legacy_teardrops no)
	)
	(paper "A4")
	(title_block
		(title "03242023_DA0F0TMBIJ0_F0T_Motherboard_J_brd_V01_OCP.brd")
		(comment 1 "Grand Teton / footprints 2148-2150 of 6105")
	)
	(layers
		(0 "F.Cu" signal "TOP")
		(4 "In1.Cu" signal "GND")
		(6 "In2.Cu" signal "IN1")
		(8 "In3.Cu" signal "GND1")
		(10 "In4.Cu" signal "IN2")
		(12 "In5.Cu" signal "GND2")
		(14 "In6.Cu" signal "IN3")
		(16 "In7.Cu" signal "GND3")
		(18 "In8.Cu" signal "VCC")
		(20 "In9.Cu" signal "VCC1")
		(22 "In10.Cu" signal "GND4")
		(24 "In11.Cu" signal "IN4")
		(26 "In12.Cu" signal "GND5")
		(28 "In13.Cu" signal "IN5")
		(30 "In14.Cu" signal "GND6")
		(32 "In15.Cu" signal "IN6")
		(34 "In16.Cu" signal "GND7")
		(2 "B.Cu" signal "BOTTOM")
		(9 "F.Adhes" user "F.Adhesive")
		(11 "B.Adhes" user "B.Adhesive")
		(13 "F.Paste" user "Package Geometry/Pastemask Top")
		(15 "B.Paste" user "Package Geometry/Pastemask Bottom")
		(5 "F.SilkS" user "Ref Des/Silkscreen Top")
		(7 "B.SilkS" user "Ref Des/Silkscreen Bottom")
		(1 "F.Mask" user "Board Geometry/Soldermask Top")
		(3 "B.Mask" user "Board Geometry/Soldermask Bottom")
		(17 "Dwgs.User" user "User.Drawings")
		(19 "Cmts.User" user "User.Comments")
		(21 "Eco1.User" user "User.Eco1")
		(23 "Eco2.User" user "User.Eco2")
		(25 "Edge.Cuts" user "Board Geometry/Outline")
		(27 "Margin" user)
		(31 "F.CrtYd" user "Package Geometry/Place Bound Top")
		(29 "B.CrtYd" user "Package Geometry/Place Bound Bottom")
		(35 "F.Fab" user "Ref Des/Assembly Top")
		(33 "B.Fab" user "Ref Des/Assembly Bottom")
	)
	(footprint ""
		(layer "F.Cu")
		(at 106.399076 -79.078836)
		(property "Reference" "D92"
			(at -52.93741 38.649402 90)
			(unlocked yes)
			(layer "F.SilkS")
			(effects
				(font
					(size 0.635 0.4064)
					(thickness 0.1524)
				)
				(justify left)
			)
		)
		(property "Value" ""
			(at 0 0 0)
			(layer "F.Fab")
			(effects
				(font
					(size 1.27 1.27)
				)
			)
		)
		(duplicate_pad_numbers_are_jumpers no)
		(fp_line
			(start -0.90678 0.4826)
			(end -0.90678 -0.4699)
			(stroke
				(width 0.1524)
				(type default)
			)
			(layer "F.SilkS")
		)
		(fp_line
			(start -0.89408 -0.4826)
			(end 0.90678 -0.4826)
			(stroke
				(width 0.1524)
				(type default)
			)
			(layer "F.SilkS")
		)
		(fp_line
			(start -0.79248 -0.4826)
			(end 1.03378 -0.4826)
			(stroke
				(width 0.1524)
				(type default)
			)
			(layer "F.SilkS")
		)
		(fp_line
			(start -0.64008 -0.4826)
			(end 1.16078 -0.4826)
			(stroke
				(width 0.1524)
				(type default)
			)
			(layer "F.SilkS")
		)
		(fp_line
			(start 0.90678 -0.4826)
			(end 0.90678 0.4826)
			(stroke
				(width 0.1524)
				(type default)
			)
			(layer "F.SilkS")
		)
		(fp_line
			(start 0.90678 0.4826)
			(end -0.90678 0.4826)
			(stroke
				(width 0.1524)
				(type default)
			)
			(layer "F.SilkS")
		)
		(fp_line
			(start 1.03378 -0.4826)
			(end 1.03378 0.4826)
			(stroke
				(width 0.1524)
				(type default)
			)
			(layer "F.SilkS")
		)
		(fp_line
			(start 1.03378 0.4826)
			(end -0.79248 0.4826)
			(stroke
				(width 0.1524)
				(type default)
			)
			(layer "F.SilkS")
		)
		(fp_line
			(start 1.16078 -0.4826)
			(end 1.16078 0.4826)
			(stroke
				(width 0.1524)
				(type default)
			)
			(layer "F.SilkS")
		)
		(fp_line
			(start 1.16078 0.4826)
			(end -0.64008 0.4826)
			(stroke
				(width 0.1524)
				(type default)
			)
			(layer "F.SilkS")
		)
		(fp_line
			(start -0.499872 -0.249936)
			(end 0.499872 -0.249936)
			(stroke
				(width 0.1)
				(type default)
			)
			(layer "F.Fab")
		)
		(fp_line
			(start -0.499872 0.249936)
			(end -0.499872 -0.249936)
			(stroke
				(width 0.1)
				(type default)
			)
			(layer "F.Fab")
		)
		(fp_line
			(start 0.499872 -0.249936)
			(end 0.499872 0.249936)
			(stroke
				(width 0.1)
				(type default)
			)
			(layer "F.Fab")
		)
		(fp_line
			(start 0.499872 0.249936)
			(end -0.499872 0.249936)
			(stroke
				(width 0.1)
				(type default)
			)
			(layer "F.Fab")
		)
		(pad "A" smd rect
			(at -0.47498 0)
			(size 0.6096 0.7112)
			(layers "F.Cu" "F.Mask" "F.Paste")
			(net "LED_PWRGD_P1V05_PCH_AUX")
		)
		(pad "C" smd rect
			(at 0.47498 0)
			(size 0.6096 0.7112)
			(layers "F.Cu" "F.Mask" "F.Paste")
			(net "LED_PWRGD_P1V05_PCH_AUX_D")
		)
	)
	(footprint ""
		(layer "F.Cu")
		(at 152.32888 -45.938948 90)
		(property "Reference" "R3594"
			(at 0 0 90)
			(layer "F.SilkS")
			(hide yes)
			(effects
				(font
					(size 1.27 1.27)
				)
			)
		)
		(property "Value" ""
			(at 0 0 90)
			(layer "F.Fab")
			(effects
				(font
					(size 1.27 1.27)
				)
			)
		)
		(duplicate_pad_numbers_are_jumpers no)
		(fp_line
			(start 0.7874 -0.4064)
			(end 0.7874 0.4064)
			(stroke
				(width 0.1524)
				(type default)
			)
			(layer "F.SilkS")
		)
		(fp_line
			(start -0.7874 -0.4064)
			(end 0.7874 -0.4064)
			(stroke
				(width 0.1524)
				(type default)
			)
			(layer "F.SilkS")
		)
		(fp_line
			(start 0.7874 0.4064)
			(end -0.7874 0.4064)
			(stroke
				(width 0.1524)
				(type default)
			)
			(layer "F.SilkS")
		)
		(fp_line
			(start -0.7874 0.4064)
			(end -0.7874 -0.4064)
			(stroke
				(width 0.1524)
				(type default)
			)
			(layer "F.SilkS")
		)
		(fp_line
			(start -0.12065 -0.305054)
			(end -0.12065 -0.2794)
			(stroke
				(width 0.1)
				(type default)
			)
			(layer "F.Fab")
		)
		(fp_line
			(start -0.67945 -0.305054)
			(end -0.12065 -0.305054)
			(stroke
				(width 0.1)
				(type default)
			)
			(layer "F.Fab")
		)
		(fp_line
			(start 0.67945 -0.3048)
			(end 0.67945 0.3048)
			(stroke
				(width 0.1)
				(type default)
			)
			(layer "F.Fab")
		)
		(fp_line
			(start 0.12065 -0.3048)
			(end 0.67945 -0.3048)
			(stroke
				(width 0.1)
				(type default)
			)
			(layer "F.Fab")
		)
		(fp_line
			(start 0.12065 -0.2794)
			(end 0.12065 -0.3048)
			(stroke
				(width 0.1)
				(type default)
			)
			(layer "F.Fab")
		)
		(fp_line
			(start -0.12065 -0.2794)
			(end 0.12065 -0.2794)
			(stroke
				(width 0.1)
				(type default)
			)
			(layer "F.Fab")
		)
		(fp_line
			(start 0.120396 0.2794)
			(end -0.12065 0.2794)
			(stroke
				(width 0.1)
				(type default)
			)
			(layer "F.Fab")
		)
		(fp_line
			(start -0.12065 0.2794)
			(end -0.12065 0.3048)
			(stroke
				(width 0.1)
				(type default)
			)
			(layer "F.Fab")
		)
		(fp_line
			(start 0.67945 0.3048)
			(end 0.120396 0.3048)
			(stroke
				(width 0.1)
				(type default)
			)
			(layer "F.Fab")
		)
		(fp_line
			(start 0.120396 0.3048)
			(end 0.120396 0.2794)
			(stroke
				(width 0.1)
				(type default)
			)
			(layer "F.Fab")
		)
		(fp_line
			(start -0.12065 0.3048)
			(end -0.67945 0.3048)
			(stroke
				(width 0.1)
				(type default)
			)
			(layer "F.Fab")
		)
		(fp_line
			(start -0.67945 0.3048)
			(end -0.67945 -0.305054)
			(stroke
				(width 0.1)
				(type default)
			)
			(layer "F.Fab")
		)
		(pad "1" smd circle
			(at -0.40005 0 90)
			(size 0 0)
			(layers "F.Cu" "F.Mask" "F.Paste")
			(net "SMB_INA230_3V3AUX_SCL")
		)
		(pad "2" smd circle
			(at 0.40005 0 90)
			(size 0 0)
			(layers "F.Cu" "F.Mask" "F.Paste")
			(net "SMB_INA230_4_3V3AUX_SCL_R")
		)
	)
	(footprint ""
		(layer "F.Cu")
		(at 260.806692 -407.416 -90)
		(property "Reference" "PR2534"
			(at 0 0 270)
			(layer "F.SilkS")
			(hide yes)
			(effects
				(font
					(size 1.27 1.27)
				)
			)
		)
		(property "Value" ""
			(at 0 0 270)
			(layer "F.Fab")
			(effects
				(font
					(size 1.27 1.27)
				)
			)
		)
		(duplicate_pad_numbers_are_jumpers no)
		(fp_line
			(start -3.9878 3.5814)
			(end -3.9878 -3.5814)
			(stroke
				(width 0.1524)
				(type default)
			)
			(layer "F.SilkS")
		)
		(fp_line
			(start 3.9878 3.5814)
			(end -3.9878 3.5814)
			(stroke
				(width 0.1524)
				(type default)
			)
			(layer "F.SilkS")
		)
		(fp_line
			(start -3.9878 -3.5814)
			(end 3.9878 -3.5814)
			(stroke
				(width 0.1524)
				(type default)
			)
			(layer "F.SilkS")
		)
		(fp_line
			(start 3.9878 -3.5814)
			(end 3.9878 3.5814)
			(stroke
				(width 0.1524)
				(type default)
			)
			(layer "F.SilkS")
		)
		(fp_line
			(start -3.5306 3.353054)
			(end -3.5306 -3.353054)
			(stroke
				(width 0.1)
				(type default)
			)
			(layer "F.Fab")
		)
		(fp_line
			(start 3.5306 3.353054)
			(end -3.5306 3.353054)
			(stroke
				(width 0.1)
				(type default)
			)
			(layer "F.Fab")
		)
		(fp_line
			(start -3.5306 -3.353054)
			(end 3.5306 -3.353054)
			(stroke
				(width 0.1)
				(type default)
			)
			(layer "F.Fab")
		)
		(fp_line
			(start 3.5306 -3.353054)
			(end 3.5306 3.353054)
			(stroke
				(width 0.1)
				(type default)
			)
			(layer "F.Fab")
		)
		(pad "1A" smd rect
			(at -2.249932 0 90)
			(size 3.2004 6.858)
			(layers "F.Cu" "F.Mask" "F.Paste")
			(net "P12V_PSU")
		)
		(pad "1B" smd rect
			(at -0.776732 0 270)
			(size 0.254 0.508)
			(layers "F.Cu" "F.Mask" "F.Paste")
			(net "P12V_HSC_SENSE2_R4_P")
		)
		(pad "2A" smd rect
			(at 2.249932 0 90)
			(size 3.2004 6.858)
			(layers "F.Cu" "F.Mask" "F.Paste")
			(net "P12V_MAIN_R")
		)
		(pad "2B" smd rect
			(at 0.776732 0 270)
			(size 0.254 0.508)
			(layers "F.Cu" "F.Mask" "F.Paste")
			(net "P12V_HSC_SENSE2_R4_N")
		)
	)
)
